# S9S_MB_2U (Grand Teton) — schematic netlist excerpt (pin names and nets, part order shuffled) for the footprints in the layout excerpt that follows; sources: Cadence DE-HDL packaged netlist, KiCad conversion of 03242023_DA0F0TMBIJ0_F0T_Motherboard_J_brd_V01_OCP.brd

R3288  Q_RES  68K 1% EMPTY  pkg 0402LF  page 166 : A = FM_P2E_SWA ; B = GND
PC2213  Q_CAP  0.01UF 50V 10% EMPTY  pkg C0402  page 192 : A = P3V3_E1S_0_R ; B = P3V3_E1S_GATE_0
PC2242  Q_CAP  22UF 16V 20% X6S  pkg C0805  page 242 : A = P12V_SCM_R ; B = GND

(kicad_pcb
	(version 20260206)
	(generator "pcbnew")
	(generator_version "10.0")
	(general
		(thickness 1.6)
		(legacy_teardrops no)
	)
	(paper "A4")
	(title_block
		(title "03242023_DA0F0TMBIJ0_F0T_Motherboard_J_brd_V01_OCP.brd")
		(comment 1 "Grand Teton / footprints 1802-1804 of 6105")
	)
	(layers
		(0 "F.Cu" signal "TOP")
		(4 "In1.Cu" signal "GND")
		(6 "In2.Cu" signal "IN1")
		(8 "In3.Cu" signal "GND1")
		(10 "In4.Cu" signal "IN2")
		(12 "In5.Cu" signal "GND2")
		(14 "In6.Cu" signal "IN3")
		(16 "In7.Cu" signal "GND3")
		(18 "In8.Cu" signal "VCC")
		(20 "In9.Cu" signal "VCC1")
		(22 "In10.Cu" signal "GND4")
		(24 "In11.Cu" signal "IN4")
		(26 "In12.Cu" signal "GND5")
		(28 "In13.Cu" signal "IN5")
		(30 "In14.Cu" signal "GND6")
		(32 "In15.Cu" signal "IN6")
		(34 "In16.Cu" signal "GND7")
		(2 "B.Cu" signal "BOTTOM")
		(9 "F.Adhes" user "F.Adhesive")
		(11 "B.Adhes" user "B.Adhesive")
		(13 "F.Paste" user "Package Geometry/Pastemask Top")
		(15 "B.Paste" user "Package Geometry/Pastemask Bottom")
		(5 "F.SilkS" user "Ref Des/Silkscreen Top")
		(7 "B.SilkS" user "Ref Des/Silkscreen Bottom")
		(1 "F.Mask" user "Board Geometry/Soldermask Top")
		(3 "B.Mask" user "Board Geometry/Soldermask Bottom")
		(17 "Dwgs.User" user "User.Drawings")
		(19 "Cmts.User" user "User.Comments")
		(21 "Eco1.User" user "User.Eco1")
		(23 "Eco2.User" user "User.Eco2")
		(25 "Edge.Cuts" user "Board Geometry/Outline")
		(27 "Margin" user)
		(31 "F.CrtYd" user "Package Geometry/Place Bound Top")
		(29 "B.CrtYd" user "Package Geometry/Place Bound Bottom")
		(35 "F.Fab" user "Ref Des/Assembly Top")
		(33 "B.Fab" user "Ref Des/Assembly Bottom")
	)
	(footprint ""
		(layer "F.Cu")
		(at 223.378522 -74.510138 180)
		(property "Reference" "PC2213"
			(at 0 0 180)
			(layer "F.SilkS")
			(hide yes)
			(effects
				(font
					(size 1.27 1.27)
				)
			)
		)
		(property "Value" ""
			(at 0 0 180)
			(layer "F.Fab")
			(effects
				(font
					(size 1.27 1.27)
				)
			)
		)
		(duplicate_pad_numbers_are_jumpers no)
		(fp_line
			(start 0.7874 0.4064)
			(end -0.7874 0.4064)
			(stroke
				(width 0.1524)
				(type default)
			)
			(layer "F.SilkS")
		)
		(fp_line
			(start 0.7874 -0.4064)
			(end 0.7874 0.4064)
			(stroke
				(width 0.1524)
				(type default)
			)
			(layer "F.SilkS")
		)
		(fp_line
			(start -0.7874 0.4064)
			(end -0.7874 -0.4064)
			(stroke
				(width 0.1524)
				(type default)
			)
			(layer "F.SilkS")
		)
		(fp_line
			(start -0.7874 -0.4064)
			(end 0.7874 -0.4064)
			(stroke
				(width 0.1524)
				(type default)
			)
			(layer "F.SilkS")
		)
		(fp_line
			(start 0.67945 0.3048)
			(end 0.120396 0.3048)
			(stroke
				(width 0.1)
				(type default)
			)
			(layer "F.Fab")
		)
		(fp_line
			(start 0.67945 -0.3048)
			(end 0.67945 0.3048)
			(stroke
				(width 0.1)
				(type default)
			)
			(layer "F.Fab")
		)
		(fp_line
			(start 0.12065 -0.2794)
			(end 0.12065 -0.3048)
			(stroke
				(width 0.1)
				(type default)
			)
			(layer "F.Fab")
		)
		(fp_line
			(start 0.12065 -0.3048)
			(end 0.67945 -0.3048)
			(stroke
				(width 0.1)
				(type default)
			)
			(layer "F.Fab")
		)
		(fp_line
			(start 0.120396 0.3048)
			(end 0.120396 0.2794)
			(stroke
				(width 0.1)
				(type default)
			)
			(layer "F.Fab")
		)
		(fp_line
			(start 0.120396 0.2794)
			(end -0.12065 0.2794)
			(stroke
				(width 0.1)
				(type default)
			)
			(layer "F.Fab")
		)
		(fp_line
			(start -0.12065 0.3048)
			(end -0.67945 0.3048)
			(stroke
				(width 0.1)
				(type default)
			)
			(layer "F.Fab")
		)
		(fp_line
			(start -0.12065 0.2794)
			(end -0.12065 0.3048)
			(stroke
				(width 0.1)
				(type default)
			)
			(layer "F.Fab")
		)
		(fp_line
			(start -0.12065 -0.2794)
			(end 0.12065 -0.2794)
			(stroke
				(width 0.1)
				(type default)
			)
			(layer "F.Fab")
		)
		(fp_line
			(start -0.12065 -0.305054)
			(end -0.12065 -0.2794)
			(stroke
				(width 0.1)
				(type default)
			)
			(layer "F.Fab")
		)
		(fp_line
			(start -0.67945 0.3048)
			(end -0.67945 -0.305054)
			(stroke
				(width 0.1)
				(type default)
			)
			(layer "F.Fab")
		)
		(fp_line
			(start -0.67945 -0.305054)
			(end -0.12065 -0.305054)
			(stroke
				(width 0.1)
				(type default)
			)
			(layer "F.Fab")
		)
		(pad "1" smd circle
			(at -0.40005 0 180)
			(size 0 0)
			(layers "F.Cu" "F.Mask" "F.Paste")
			(net "P3V3_E1S_0_R")
		)
		(pad "2" smd circle
			(at 0.40005 0 180)
			(size 0 0)
			(layers "F.Cu" "F.Mask" "F.Paste")
			(net "P3V3_E1S_GATE_0")
		)
	)
	(footprint ""
		(layer "F.Cu")
		(at 175.06188 -21.173948 180)
		(property "Reference" "PC2242"
			(at 0 0 180)
			(layer "F.SilkS")
			(hide yes)
			(effects
				(font
					(size 1.27 1.27)
				)
			)
		)
		(property "Value" ""
			(at 0 0 180)
			(layer "F.Fab")
			(effects
				(font
					(size 1.27 1.27)
				)
			)
		)
		(duplicate_pad_numbers_are_jumpers no)
		(fp_line
			(start 1.524 0.762)
			(end -1.524 0.762)
			(stroke
				(width 0.1524)
				(type default)
			)
			(layer "F.SilkS")
		)
		(fp_line
			(start 1.524 -0.762)
			(end 1.524 0.762)
			(stroke
				(width 0.1524)
				(type default)
			)
			(layer "F.SilkS")
		)
		(fp_line
			(start -1.524 0.762)
			(end -1.524 -0.762)
			(stroke
				(width 0.1524)
				(type default)
			)
			(layer "F.SilkS")
		)
		(fp_line
			(start -1.524 -0.762)
			(end 1.524 -0.762)
			(stroke
				(width 0.1524)
				(type default)
			)
			(layer "F.SilkS")
		)
		(fp_line
			(start 1.1049 0.724916)
			(end 1.1049 -0.724916)
			(stroke
				(width 0.1)
				(type default)
			)
			(layer "F.Fab")
		)
		(fp_line
			(start 1.1049 -0.724916)
			(end -1.1049 -0.724916)
			(stroke
				(width 0.1)
				(type default)
			)
			(layer "F.Fab")
		)
		(fp_line
			(start -1.1049 0.724916)
			(end 1.1049 0.724916)
			(stroke
				(width 0.1)
				(type default)
			)
			(layer "F.Fab")
		)
		(fp_line
			(start -1.1049 -0.724916)
			(end -1.1049 0.724916)
			(stroke
				(width 0.1)
				(type default)
			)
			(layer "F.Fab")
		)
		(pad "1" smd rect
			(at -0.889 0)
			(size 1.016 1.27)
			(layers "F.Cu" "F.Mask" "F.Paste")
			(net "P12V_SCM_R")
		)
		(pad "2" smd rect
			(at 0.889 0)
			(size 1.016 1.27)
			(layers "F.Cu" "F.Mask" "F.Paste")
			(net "GND")
		)
	)
	(footprint ""
		(layer "F.Cu")
		(at 15.436596 -388.161276 180)
		(property "Reference" "R3288"
			(at 0 0 180)
			(layer "F.SilkS")
			(hide yes)
			(effects
				(font
					(size 1.27 1.27)
				)
			)
		)
		(property "Value" ""
			(at 0 0 180)
			(layer "F.Fab")
			(effects
				(font
					(size 1.27 1.27)
				)
			)
		)
		(duplicate_pad_numbers_are_jumpers no)
		(fp_line
			(start 0.7874 0.4064)
			(end -0.7874 0.4064)
			(stroke
				(width 0.1524)
				(type default)
			)
			(layer "F.SilkS")
		)
		(fp_line
			(start 0.7874 -0.4064)
			(end 0.7874 0.4064)
			(stroke
				(width 0.1524)
				(type default)
			)
			(layer "F.SilkS")
		)
		(fp_line
			(start -0.7874 0.4064)
			(end -0.7874 -0.4064)
			(stroke
				(width 0.1524)
				(type default)
			)
			(layer "F.SilkS")
		)
		(fp_line
			(start -0.7874 -0.4064)
			(end 0.7874 -0.4064)
			(stroke
				(width 0.1524)
				(type default)
			)
			(layer "F.SilkS")
		)
		(fp_line
			(start 0.67945 0.3048)
			(end 0.120396 0.3048)
			(stroke
				(width 0.1)
				(type default)
			)
			(layer "F.Fab")
		)
		(fp_line
			(start 0.67945 -0.3048)
			(end 0.67945 0.3048)
			(stroke
				(width 0.1)
				(type default)
			)
			(layer "F.Fab")
		)
		(fp_line
			(start 0.12065 -0.2794)
			(end 0.12065 -0.3048)
			(stroke
				(width 0.1)
				(type default)
			)
			(layer "F.Fab")
		)
		(fp_line
			(start 0.12065 -0.3048)
			(end 0.67945 -0.3048)
			(stroke
				(width 0.1)
				(type default)
			)
			(layer "F.Fab")
		)
		(fp_line
			(start 0.120396 0.3048)
			(end 0.120396 0.2794)
			(stroke
				(width 0.1)
				(type default)
			)
			(layer "F.Fab")
		)
		(fp_line
			(start 0.120396 0.2794)
			(end -0.12065 0.2794)
			(stroke
				(width 0.1)
				(type default)
			)
			(layer "F.Fab")
		)
		(fp_line
			(start -0.12065 0.3048)
			(end -0.67945 0.3048)
			(stroke
				(width 0.1)
				(type default)
			)
			(layer "F.Fab")
		)
		(fp_line
			(start -0.12065 0.2794)
			(end -0.12065 0.3048)
			(stroke
				(width 0.1)
				(type default)
			)
			(layer "F.Fab")
		)
		(fp_line
			(start -0.12065 -0.2794)
			(end 0.12065 -0.2794)
			(stroke
				(width 0.1)
				(type default)
			)
			(layer "F.Fab")
		)
		(fp_line
			(start -0.12065 -0.305054)
			(end -0.12065 -0.2794)
			(stroke
				(width 0.1)
				(type default)
			)
			(layer "F.Fab")
		)
		(fp_line
			(start -0.67945 0.3048)
			(end -0.67945 -0.305054)
			(stroke
				(width 0.1)
				(type default)
			)
			(layer "F.Fab")
		)
		(fp_line
			(start -0.67945 -0.305054)
			(end -0.12065 -0.305054)
			(stroke
				(width 0.1)
				(type default)
			)
			(layer "F.Fab")
		)
		(pad "1" smd circle
			(at -0.40005 0 180)
			(size 0 0)
			(layers "F.Cu" "F.Mask" "F.Paste")
			(net "FM_P2E_SWA")
		)
		(pad "2" smd circle
			(at 0.40005 0 180)
			(size 0 0)
			(layers "F.Cu" "F.Mask" "F.Paste")
			(net "GND")
		)
	)
)
